(kicad_pcb
	(version 20260206)
	(generator "pcbnew")
	(generator_version "10.0")
	(general
		(thickness 1.6)
		(legacy_teardrops no)
	)
	(paper "A4")
	(title_block
		(title "Bryce Canyon_R.DPB_16317-1_OCP.brd")
		(comment 1 "Bryce Canyon / footprints 570-575 of 2099")
	)
	(layers
		(0 "F.Cu" signal "TOP")
		(4 "In1.Cu" signal "L2GND")
		(6 "In2.Cu" signal "L3")
		(8 "In3.Cu" signal "L4VCC")
		(10 "In4.Cu" signal "L5VCC")
		(12 "In5.Cu" signal "L6")
		(14 "In6.Cu" signal "L7GND")
		(2 "B.Cu" signal "BOTTOM")
		(9 "F.Adhes" user "F.Adhesive")
		(11 "B.Adhes" user "B.Adhesive")
		(13 "F.Paste" user "Package Geometry/Pastemask Top")
		(15 "B.Paste" user "Package Geometry/Pastemask Bottom")
		(5 "F.SilkS" user "Ref Des/Silkscreen Top")
		(7 "B.SilkS" user "Ref Des/Silkscreen Bottom")
		(1 "F.Mask" user "Board Geometry/Soldermask Top")
		(3 "B.Mask" user "Board Geometry/Soldermask Bottom")
		(17 "Dwgs.User" user "User.Drawings")
		(19 "Cmts.User" user "User.Comments")
		(21 "Eco1.User" user "User.Eco1")
		(23 "Eco2.User" user "User.Eco2")
		(25 "Edge.Cuts" user "Board Geometry/Outline")
		(27 "Margin" user)
		(31 "F.CrtYd" user "Package Geometry/Place Bound Top")
		(29 "B.CrtYd" user "Package Geometry/Place Bound Bottom")
		(35 "F.Fab" user "Ref Des/Assembly Top")
		(33 "B.Fab" user "Ref Des/Assembly Bottom")
	)
	(footprint ""
		(layer "F.Cu")
		(at 177.6984 -9.9314)
		(property "Reference" "R752"
			(at 0 0 0)
			(layer "F.SilkS")
			(hide yes)
			(effects
				(font
					(size 1.27 1.27)
				)
			)
		)
		(property "Value" "300KR2F-GP"
			(at 0.064008 -3.993896 0)
			(unlocked yes)
			(layer "F.Fab")
			(hide yes)
			(effects
				(font
					(size 1.016 1.016)
					(thickness 0.1524)
				)
			)
		)
		(property "Device Type" "R402H16"
			(at 0.064008 -5.517896 0)
			(unlocked yes)
			(layer "F.Fab")
			(hide yes)
			(effects
				(font
					(size 1.016 1.016)
					(thickness 0.1524)
				)
			)
		)
		(duplicate_pad_numbers_are_jumpers no)
		(fp_line
			(start -0.508 -0.9398)
			(end -0.508 0.9398)
			(stroke
				(width 0.1524)
				(type default)
			)
			(layer "F.SilkS")
		)
		(fp_line
			(start 0.508 -0.9398)
			(end -0.508 -0.9398)
			(stroke
				(width 0.1524)
				(type default)
			)
			(layer "F.SilkS")
		)
		(fp_rect
			(start -0.508 0.9398)
			(end 0.508 -0.9398)
			(stroke
				(width 0)
				(type default)
			)
			(fill no)
			(layer "F.CrtYd")
		)
		(fp_rect
			(start -0.508 0.9398)
			(end 0.508 -0.9398)
			(stroke
				(width 0)
				(type default)
			)
			(fill no)
			(layer "F.Fab")
		)
		(pad "1" smd custom
			(at 0 -0.4445)
			(size 0.1397 0.1397)
			(layers "F.Cu" "F.Mask" "F.Paste")
			(net "SW_HDD_N29")
			(options
				(clearance outline)
				(anchor circle)
			)
			(primitives
				(gr_poly
					(pts
						(arc
							(start -0.1778 -0.2794)
							(mid -0.249642 -0.249642)
							(end -0.2794 -0.1778)
						)
						(arc
							(start -0.2794 0.1778)
							(mid -0.249642 0.249642)
							(end -0.1778 0.2794)
						)
						(arc
							(start 0.1778 0.2794)
							(mid 0.249642 0.249642)
							(end 0.2794 0.1778)
						)
						(arc
							(start 0.2794 -0.1778)
							(mid 0.249642 -0.249642)
							(end 0.1778 -0.2794)
						)
					)
					(width 0)
					(fill yes)
				)
			)
		)
		(pad "2" smd custom
			(at 0 0.4445)
			(size 0.1397 0.1397)
			(layers "F.Cu" "F.Mask" "F.Paste")
			(net "P12V_B")
			(options
				(clearance outline)
				(anchor circle)
			)
			(primitives
				(gr_poly
					(pts
						(arc
							(start -0.1778 -0.2794)
							(mid -0.249642 -0.249642)
							(end -0.2794 -0.1778)
						)
						(arc
							(start -0.2794 0.1778)
							(mid -0.249642 0.249642)
							(end -0.1778 0.2794)
						)
						(arc
							(start 0.1778 0.2794)
							(mid 0.249642 0.249642)
							(end 0.2794 0.1778)
						)
						(arc
							(start 0.2794 -0.1778)
							(mid 0.249642 -0.249642)
							(end 0.1778 -0.2794)
						)
					)
					(width 0)
					(fill yes)
				)
			)
		)
	)
	(footprint ""
		(layer "F.Cu")
		(at 127 -372.618)
		(property "Reference" "R937"
			(at 0 0 0)
			(layer "F.SilkS")
			(hide yes)
			(effects
				(font
					(size 1.27 1.27)
				)
			)
		)
		(property "Value" "10KR2F-2-GP"
			(at 0.064008 -3.993896 0)
			(unlocked yes)
			(layer "F.Fab")
			(hide yes)
			(effects
				(font
					(size 1.016 1.016)
					(thickness 0.1524)
				)
			)
		)
		(property "Device Type" "R402H16"
			(at 0.064008 -5.517896 0)
			(unlocked yes)
			(layer "F.Fab")
			(hide yes)
			(effects
				(font
					(size 1.016 1.016)
					(thickness 0.1524)
				)
			)
		)
		(duplicate_pad_numbers_are_jumpers no)
		(fp_line
			(start -0.508 -0.9398)
			(end -0.508 0.9398)
			(stroke
				(width 0.1524)
				(type default)
			)
			(layer "F.SilkS")
		)
		(fp_line
			(start 0.508 -0.9398)
			(end -0.508 -0.9398)
			(stroke
				(width 0.1524)
				(type default)
			)
			(layer "F.SilkS")
		)
		(fp_rect
			(start -0.508 0.9398)
			(end 0.508 -0.9398)
			(stroke
				(width 0)
				(type default)
			)
			(fill no)
			(layer "F.CrtYd")
		)
		(fp_rect
			(start -0.508 0.9398)
			(end 0.508 -0.9398)
			(stroke
				(width 0)
				(type default)
			)
			(fill no)
			(layer "F.Fab")
		)
		(pad "1" smd custom
			(at 0 -0.4445)
			(size 0.1397 0.1397)
			(layers "F.Cu" "F.Mask" "F.Paste")
			(net "GND")
			(options
				(clearance outline)
				(anchor circle)
			)
			(primitives
				(gr_poly
					(pts
						(arc
							(start -0.1778 -0.2794)
							(mid -0.249642 -0.249642)
							(end -0.2794 -0.1778)
						)
						(arc
							(start -0.2794 0.1778)
							(mid -0.249642 0.249642)
							(end -0.1778 0.2794)
						)
						(arc
							(start 0.1778 0.2794)
							(mid 0.249642 0.249642)
							(end 0.2794 0.1778)
						)
						(arc
							(start 0.2794 -0.1778)
							(mid 0.249642 -0.249642)
							(end 0.1778 -0.2794)
						)
					)
					(width 0)
					(fill yes)
				)
			)
		)
		(pad "2" smd custom
			(at 0 0.4445)
			(size 0.1397 0.1397)
			(layers "F.Cu" "F.Mask" "F.Paste")
			(net "FANTACH_R1")
			(options
				(clearance outline)
				(anchor circle)
			)
			(primitives
				(gr_poly
					(pts
						(arc
							(start -0.1778 -0.2794)
							(mid -0.249642 -0.249642)
							(end -0.2794 -0.1778)
						)
						(arc
							(start -0.2794 0.1778)
							(mid -0.249642 0.249642)
							(end -0.1778 0.2794)
						)
						(arc
							(start 0.1778 0.2794)
							(mid 0.249642 0.249642)
							(end 0.2794 0.1778)
						)
						(arc
							(start 0.2794 -0.1778)
							(mid 0.249642 -0.249642)
							(end 0.1778 -0.2794)
						)
					)
					(width 0)
					(fill yes)
				)
			)
		)
	)
	(footprint ""
		(layer "F.Cu")
		(at 177.8 -262.001 -90)
		(property "Reference" "C96"
			(at 0 0 270)
			(layer "F.SilkS")
			(hide yes)
			(effects
				(font
					(size 1.27 1.27)
				)
			)
		)
		(property "Value" "SC10U16V6KX-2GP"
			(at -0.0762 -5.1308 270)
			(unlocked yes)
			(layer "F.Fab")
			(hide yes)
			(effects
				(font
					(size 1.016 1.016)
					(thickness 0.1524)
				)
			)
		)
		(property "Device Type" "C1206H71"
			(at -0.127 -6.6548 270)
			(unlocked yes)
			(layer "F.Fab")
			(hide yes)
			(effects
				(font
					(size 1.016 1.016)
					(thickness 0.1524)
				)
			)
		)
		(duplicate_pad_numbers_are_jumpers no)
		(fp_line
			(start -1.016 2.2352)
			(end -1.016 0.8382)
			(stroke
				(width 0.1524)
				(type default)
			)
			(layer "F.SilkS")
		)
		(fp_line
			(start 1.016 2.2352)
			(end -1.016 2.2352)
			(stroke
				(width 0.1524)
				(type default)
			)
			(layer "F.SilkS")
		)
		(fp_line
			(start 1.016 0.8382)
			(end 1.016 2.2352)
			(stroke
				(width 0.1524)
				(type default)
			)
			(layer "F.SilkS")
		)
		(fp_line
			(start -1.016 -0.8382)
			(end -1.016 -2.2352)
			(stroke
				(width 0.1524)
				(type default)
			)
			(layer "F.SilkS")
		)
		(fp_line
			(start -1.016 -2.2352)
			(end 1.016 -2.2352)
			(stroke
				(width 0.1524)
				(type default)
			)
			(layer "F.SilkS")
		)
		(fp_line
			(start 1.016 -2.2352)
			(end 1.016 -0.8382)
			(stroke
				(width 0.1524)
				(type default)
			)
			(layer "F.SilkS")
		)
		(fp_rect
			(start -1.0922 2.3114)
			(end 1.0922 -2.3114)
			(stroke
				(width 0)
				(type default)
			)
			(fill no)
			(layer "F.CrtYd")
		)
		(fp_poly
			(pts
				(xy 1.0922 -2.3114) (xy 1.0922 2.3114) (xy -1.0922 2.3114) (xy -1.0922 -2.3114)
			)
			(stroke
				(width 0)
				(type default)
			)
			(fill no)
			(layer "F.Fab")
		)
		(pad "1" smd rect
			(at 0 -1.397 270)
			(size 1.651 1.27)
			(layers "F.Cu" "F.Mask" "F.Paste")
			(net "P5V_HDD5")
		)
		(pad "2" smd rect
			(at 0 1.397 270)
			(size 1.651 1.27)
			(layers "F.Cu" "F.Mask" "F.Paste")
			(net "GND")
		)
	)
	(footprint ""
		(layer "F.Cu")
		(at 190.8556 -263.144 -90)
		(property "Reference" "R239"
			(at 0 0 270)
			(layer "F.SilkS")
			(hide yes)
			(effects
				(font
					(size 1.27 1.27)
				)
			)
		)
		(property "Value" "10KR2F-2-GP"
			(at 0.064008 -3.993896 270)
			(unlocked yes)
			(layer "F.Fab")
			(hide yes)
			(effects
				(font
					(size 1.016 1.016)
					(thickness 0.1524)
				)
			)
		)
		(property "Device Type" "R402H16"
			(at 0.064008 -5.517896 270)
			(unlocked yes)
			(layer "F.Fab")
			(hide yes)
			(effects
				(font
					(size 1.016 1.016)
					(thickness 0.1524)
				)
			)
		)
		(duplicate_pad_numbers_are_jumpers no)
		(fp_line
			(start -0.508 -0.9398)
			(end -0.508 0.9398)
			(stroke
				(width 0.1524)
				(type default)
			)
			(layer "F.SilkS")
		)
		(fp_line
			(start 0.508 -0.9398)
			(end -0.508 -0.9398)
			(stroke
				(width 0.1524)
				(type default)
			)
			(layer "F.SilkS")
		)
		(fp_rect
			(start -0.508 0.9398)
			(end 0.508 -0.9398)
			(stroke
				(width 0)
				(type default)
			)
			(fill no)
			(layer "F.CrtYd")
		)
		(fp_rect
			(start -0.508 0.9398)
			(end 0.508 -0.9398)
			(stroke
				(width 0)
				(type default)
			)
			(fill no)
			(layer "F.Fab")
		)
		(pad "1" smd custom
			(at 0 -0.4445 270)
			(size 0.1397 0.1397)
			(layers "F.Cu" "F.Mask" "F.Paste")
			(net "P3V3_STBY_B")
			(options
				(clearance outline)
				(anchor circle)
			)
			(primitives
				(gr_poly
					(pts
						(arc
							(start -0.1778 -0.2794)
							(mid -0.249642 -0.249642)
							(end -0.2794 -0.1778)
						)
						(arc
							(start -0.2794 0.1778)
							(mid -0.249642 0.249642)
							(end -0.1778 0.2794)
						)
						(arc
							(start 0.1778 0.2794)
							(mid 0.249642 0.249642)
							(end 0.2794 0.1778)
						)
						(arc
							(start 0.2794 -0.1778)
							(mid 0.249642 -0.249642)
							(end 0.1778 -0.2794)
						)
					)
					(width 0)
					(fill yes)
				)
			)
		)
		(pad "2" smd custom
			(at 0 0.4445 270)
			(size 0.1397 0.1397)
			(layers "F.Cu" "F.Mask" "F.Paste")
			(net "HDD_PRSNT_5")
			(options
				(clearance outline)
				(anchor circle)
			)
			(primitives
				(gr_poly
					(pts
						(arc
							(start -0.1778 -0.2794)
							(mid -0.249642 -0.249642)
							(end -0.2794 -0.1778)
						)
						(arc
							(start -0.2794 0.1778)
							(mid -0.249642 0.249642)
							(end -0.1778 0.2794)
						)
						(arc
							(start 0.1778 0.2794)
							(mid 0.249642 0.249642)
							(end 0.2794 0.1778)
						)
						(arc
							(start 0.2794 -0.1778)
							(mid 0.249642 -0.249642)
							(end 0.1778 -0.2794)
						)
					)
					(width 0)
					(fill yes)
				)
			)
		)
	)
	(footprint ""
		(layer "F.Cu")
		(at 207.3402 -198.374 90)
		(property "Reference" "R31"
			(at 0 0 90)
			(layer "F.SilkS")
			(hide yes)
			(effects
				(font
					(size 1.27 1.27)
				)
			)
		)
		(property "Value" "4K7R2F-GP"
			(at 0.064008 -3.993896 90)
			(unlocked yes)
			(layer "F.Fab")
			(hide yes)
			(effects
				(font
					(size 1.016 1.016)
					(thickness 0.1524)
				)
			)
		)
		(property "Device Type" "R402H16"
			(at 0.064008 -5.517896 90)
			(unlocked yes)
			(layer "F.Fab")
			(hide yes)
			(effects
				(font
					(size 1.016 1.016)
					(thickness 0.1524)
				)
			)
		)
		(duplicate_pad_numbers_are_jumpers no)
		(fp_line
			(start 0.508 -0.9398)
			(end -0.508 -0.9398)
			(stroke
				(width 0.1524)
				(type default)
			)
			(layer "F.SilkS")
		)
		(fp_line
			(start -0.508 -0.9398)
			(end -0.508 0.9398)
			(stroke
				(width 0.1524)
				(type default)
			)
			(layer "F.SilkS")
		)
		(fp_rect
			(start -0.508 0.9398)
			(end 0.508 -0.9398)
			(stroke
				(width 0)
				(type default)
			)
			(fill no)
			(layer "F.CrtYd")
		)
		(fp_rect
			(start -0.508 0.9398)
			(end 0.508 -0.9398)
			(stroke
				(width 0)
				(type default)
			)
			(fill no)
			(layer "F.Fab")
		)
		(pad "1" smd custom
			(at 0 -0.4445 90)
			(size 0.1397 0.1397)
			(layers "F.Cu" "F.Mask" "F.Paste")
			(net "P3V3_STBY_B")
			(options
				(clearance outline)
				(anchor circle)
			)
			(primitives
				(gr_poly
					(pts
						(arc
							(start -0.1778 -0.2794)
							(mid -0.249642 -0.249642)
							(end -0.2794 -0.1778)
						)
						(arc
							(start -0.2794 0.1778)
							(mid -0.249642 0.249642)
							(end -0.1778 0.2794)
						)
						(arc
							(start 0.1778 0.2794)
							(mid 0.249642 0.249642)
							(end 0.2794 0.1778)
						)
						(arc
							(start 0.2794 -0.1778)
							(mid 0.249642 -0.249642)
							(end 0.1778 -0.2794)
						)
					)
					(width 0)
					(fill yes)
				)
			)
		)
		(pad "2" smd custom
			(at 0 0.4445 90)
			(size 0.1397 0.1397)
			(layers "F.Cu" "F.Mask" "F.Paste")
			(net "IO_EXP2_HDD_FAULT_A1")
			(options
				(clearance outline)
				(anchor circle)
			)
			(primitives
				(gr_poly
					(pts
						(arc
							(start -0.1778 -0.2794)
							(mid -0.249642 -0.249642)
							(end -0.2794 -0.1778)
						)
						(arc
							(start -0.2794 0.1778)
							(mid -0.249642 0.249642)
							(end -0.1778 0.2794)
						)
						(arc
							(start 0.1778 0.2794)
							(mid 0.249642 0.249642)
							(end 0.2794 0.1778)
						)
						(arc
							(start 0.2794 -0.1778)
							(mid 0.249642 -0.249642)
							(end 0.1778 -0.2794)
						)
					)
					(width 0)
					(fill yes)
				)
			)
		)
	)
	(footprint ""
		(layer "F.Cu")
		(at 338.709 -143.891 90)
		(property "Reference" "C273"
			(at 0 0 90)
			(layer "F.SilkS")
			(hide yes)
			(effects
				(font
					(size 1.27 1.27)
				)
			)
		)
		(property "Value" "SCD033U25V2KX-GP"
			(at 1.1811 -2.7051 90)
			(unlocked yes)
			(layer "F.Fab")
			(hide yes)
			(effects
				(font
					(size 1.016 1.016)
					(thickness 0.1524)
				)
			)
		)
		(property "Device Type" "C402H22"
			(at 1.1811 -4.2291 90)
			(unlocked yes)
			(layer "F.Fab")
			(hide yes)
			(effects
				(font
					(size 1.016 1.016)
					(thickness 0.1524)
				)
			)
		)
		(duplicate_pad_numbers_are_jumpers no)
		(fp_rect
			(start -0.4318 0.9525)
			(end 0.4318 -0.9525)
			(stroke
				(width 0)
				(type default)
			)
			(fill no)
			(layer "F.CrtYd")
		)
		(fp_rect
			(start -0.4318 0.9525)
			(end 0.4318 -0.9525)
			(stroke
				(width 0)
				(type default)
			)
			(fill no)
			(layer "F.Fab")
		)
		(pad "1" smd custom
			(at 0 -0.4445 90)
			(size 0.1524 0.1524)
			(layers "F.Cu" "F.Mask" "F.Paste")
			(net "P12V_B")
			(options
				(clearance outline)
				(anchor circle)
			)
			(primitives
				(gr_poly
					(pts
						(arc
							(start 0.3048 -0.2032)
							(mid 0.275042 -0.275042)
							(end 0.2032 -0.3048)
						)
						(arc
							(start -0.2032 -0.3048)
							(mid -0.275042 -0.275042)
							(end -0.3048 -0.2032)
						)
						(arc
							(start -0.3048 0.2032)
							(mid -0.275042 0.275042)
							(end -0.2032 0.3048)
						)
						(arc
							(start 0.2032 0.3048)
							(mid 0.275042 0.275042)
							(end 0.3048 0.2032)
						)
					)
					(width 0)
					(fill yes)
				)
			)
		)
		(pad "2" smd custom
			(at 0 0.4445 90)
			(size 0.1524 0.1524)
			(layers "F.Cu" "F.Mask" "F.Paste")
			(net "SW_HDD_N18")
			(options
				(clearance outline)
				(anchor circle)
			)
			(primitives
				(gr_poly
					(pts
						(arc
							(start 0.3048 -0.2032)
							(mid 0.275042 -0.275042)
							(end 0.2032 -0.3048)
						)
						(arc
							(start -0.2032 -0.3048)
							(mid -0.275042 -0.275042)
							(end -0.3048 -0.2032)
						)
						(arc
							(start -0.3048 0.2032)
							(mid -0.275042 0.275042)
							(end -0.2032 0.3048)
						)
						(arc
							(start 0.2032 0.3048)
							(mid 0.275042 0.275042)
							(end 0.3048 0.2032)
						)
					)
					(width 0)
					(fill yes)
				)
			)
		)
	)
)
